# BASEBOARD_FAB2 (Tioga Pass) — schematic netlist excerpt (pin names and nets, part order shuffled) for the footprints in the layout excerpt that follows; sources: Cadence DE-HDL packaged netlist, KiCad conversion of Wiwynn_Tioga_Pass_MB.brd

R9F8  RES  10.0K 1% CHIP  pkg 0402  page 238 : A = GND ; B = VR_P1V15_BMC_STBY_FB
C6A4  CAP  22UF 4V 20% X6S  pkg 0805LF  page 219 : A = PVDDQ_DEF ; B = GND
R8D28  RES  1.00K 1% CHIP  pkg 0402  page 167 : A = P3V3_STBY ; B = PU_AT24C64_A2

(kicad_pcb
	(version 20260206)
	(generator "pcbnew")
	(generator_version "10.0")
	(general
		(thickness 1.6)
		(legacy_teardrops no)
	)
	(paper "A4")
	(title_block
		(title "Wiwynn_Tioga_Pass_MB.brd")
		(comment 1 "Tioga Pass / footprints 2121-2123 of 4770")
	)
	(layers
		(0 "F.Cu" signal "TOP")
		(4 "In1.Cu" signal "L2GND")
		(6 "In2.Cu" signal "L3")
		(8 "In3.Cu" signal "L4GND")
		(10 "In4.Cu" signal "L5")
		(12 "In5.Cu" signal "L6GND")
		(14 "In6.Cu" signal "L7VCC")
		(16 "In7.Cu" signal "L8VCC")
		(18 "In8.Cu" signal "L9GND")
		(20 "In9.Cu" signal "L10")
		(22 "In10.Cu" signal "L11GND")
		(24 "In11.Cu" signal "L12")
		(26 "In12.Cu" signal "L13GND")
		(2 "B.Cu" signal "BOTTOM")
		(9 "F.Adhes" user "F.Adhesive")
		(11 "B.Adhes" user "B.Adhesive")
		(13 "F.Paste" user "Package Geometry/Pastemask Top")
		(15 "B.Paste" user "Package Geometry/Pastemask Bottom")
		(5 "F.SilkS" user "Ref Des/Silkscreen Top")
		(7 "B.SilkS" user "Ref Des/Silkscreen Bottom")
		(1 "F.Mask" user "Board Geometry/Soldermask Top")
		(3 "B.Mask" user "Board Geometry/Soldermask Bottom")
		(17 "Dwgs.User" user "User.Drawings")
		(19 "Cmts.User" user "User.Comments")
		(21 "Eco1.User" user "User.Eco1")
		(23 "Eco2.User" user "User.Eco2")
		(25 "Edge.Cuts" user "Board Geometry/Outline")
		(27 "Margin" user)
		(31 "F.CrtYd" user "Package Geometry/Place Bound Top")
		(29 "B.CrtYd" user "Package Geometry/Place Bound Bottom")
		(35 "F.Fab" user "Ref Des/Assembly Top")
		(33 "B.Fab" user "Ref Des/Assembly Bottom")
	)
	(footprint ""
		(layer "F.Cu")
		(at 409.1305 -50.038 90)
		(property "Reference" "R8D28"
			(at 0 0 90)
			(layer "F.SilkS")
			(hide yes)
			(effects
				(font
					(size 1.27 1.27)
				)
			)
		)
		(property "Value" ""
			(at 0 0 90)
			(layer "F.Fab")
			(effects
				(font
					(size 1.27 1.27)
				)
			)
		)
		(duplicate_pad_numbers_are_jumpers no)
		(fp_poly
			(pts
				(xy -0.2794 -0.1016) (xy 0.2794 -0.1016) (xy 0.2794 0.9906) (xy -0.2794 0.9906)
			)
			(stroke
				(width 0)
				(type default)
			)
			(fill no)
			(layer "F.CrtYd")
		)
		(fp_line
			(start 0.2794 -0.1016)
			(end -0.2794 -0.1016)
			(stroke
				(width 0.1)
				(type default)
			)
			(layer "F.Fab")
		)
		(fp_line
			(start -0.2794 -0.1016)
			(end -0.2794 0.9906)
			(stroke
				(width 0.1)
				(type default)
			)
			(layer "F.Fab")
		)
		(fp_line
			(start 0.2794 0.9906)
			(end 0.2794 -0.1016)
			(stroke
				(width 0.1)
				(type default)
			)
			(layer "F.Fab")
		)
		(fp_line
			(start -0.2794 0.9906)
			(end 0.2794 0.9906)
			(stroke
				(width 0.1)
				(type default)
			)
			(layer "F.Fab")
		)
		(pad "1" smd rect
			(at 0 0 90)
			(size 0.508 0.508)
			(layers "F.Cu" "F.Mask" "F.Paste")
			(net "P3V3_STBY")
		)
		(pad "2" smd rect
			(at 0 0.889 90)
			(size 0.508 0.508)
			(layers "F.Cu" "F.Mask" "F.Paste")
			(net "PU_AT24C64_A2")
		)
		(zone
			(layer "F.Cu")
			(hatch none 0.5)
			(connect_pads
				(clearance 0)
			)
			(min_thickness 0.25)
			(keepout
				(tracks allowed)
				(vias not_allowed)
				(pads allowed)
				(copperpour not_allowed)
				(footprints allowed)
			)
			(placement
				(enabled no)
				(sheetname "")
			)
			(fill
				(thermal_gap 0.5)
				(thermal_bridge_width 0.5)
				(island_removal_mode 0)
			)
			(polygon
				(pts
					(xy 409.3845 -49.784) (xy 409.3845 -50.292) (xy 409.7655 -50.292) (xy 409.7655 -49.784)
				)
			)
		)
		(zone
			(layer "F.Cu")
			(hatch none 0.5)
			(connect_pads
				(clearance 0)
			)
			(min_thickness 0.25)
			(keepout
				(tracks not_allowed)
				(vias allowed)
				(pads allowed)
				(copperpour not_allowed)
				(footprints allowed)
			)
			(placement
				(enabled no)
				(sheetname "")
			)
			(fill
				(thermal_gap 0.5)
				(thermal_bridge_width 0.5)
				(island_removal_mode 0)
			)
			(polygon
				(pts
					(xy 409.7655 -49.784) (xy 409.7655 -50.292) (xy 409.3845 -50.292) (xy 409.3845 -49.784)
				)
			)
		)
	)
	(footprint ""
		(layer "F.Cu")
		(at 458.177392 -38.591998 90)
		(property "Reference" "R9F8"
			(at 0 0 90)
			(layer "F.SilkS")
			(hide yes)
			(effects
				(font
					(size 1.27 1.27)
				)
			)
		)
		(property "Value" ""
			(at 0 0 90)
			(layer "F.Fab")
			(effects
				(font
					(size 1.27 1.27)
				)
			)
		)
		(duplicate_pad_numbers_are_jumpers no)
		(fp_poly
			(pts
				(xy -0.2794 -0.1016) (xy 0.2794 -0.1016) (xy 0.2794 0.9906) (xy -0.2794 0.9906)
			)
			(stroke
				(width 0)
				(type default)
			)
			(fill no)
			(layer "F.CrtYd")
		)
		(fp_line
			(start 0.2794 -0.1016)
			(end -0.2794 -0.1016)
			(stroke
				(width 0.1)
				(type default)
			)
			(layer "F.Fab")
		)
		(fp_line
			(start -0.2794 -0.1016)
			(end -0.2794 0.9906)
			(stroke
				(width 0.1)
				(type default)
			)
			(layer "F.Fab")
		)
		(fp_line
			(start 0.2794 0.9906)
			(end 0.2794 -0.1016)
			(stroke
				(width 0.1)
				(type default)
			)
			(layer "F.Fab")
		)
		(fp_line
			(start -0.2794 0.9906)
			(end 0.2794 0.9906)
			(stroke
				(width 0.1)
				(type default)
			)
			(layer "F.Fab")
		)
		(pad "1" smd rect
			(at 0 0 90)
			(size 0.508 0.508)
			(layers "F.Cu" "F.Mask" "F.Paste")
			(net "GND")
		)
		(pad "2" smd rect
			(at 0 0.889 90)
			(size 0.508 0.508)
			(layers "F.Cu" "F.Mask" "F.Paste")
			(net "VR_P1V15_BMC_STBY_FB")
		)
		(zone
			(layer "F.Cu")
			(hatch none 0.5)
			(connect_pads
				(clearance 0)
			)
			(min_thickness 0.25)
			(keepout
				(tracks allowed)
				(vias not_allowed)
				(pads allowed)
				(copperpour not_allowed)
				(footprints allowed)
			)
			(placement
				(enabled no)
				(sheetname "")
			)
			(fill
				(thermal_gap 0.5)
				(thermal_bridge_width 0.5)
				(island_removal_mode 0)
			)
			(polygon
				(pts
					(xy 458.431392 -38.337998) (xy 458.431392 -38.845998) (xy 458.812392 -38.845998) (xy 458.812392 -38.337998)
				)
			)
		)
		(zone
			(layer "F.Cu")
			(hatch none 0.5)
			(connect_pads
				(clearance 0)
			)
			(min_thickness 0.25)
			(keepout
				(tracks not_allowed)
				(vias allowed)
				(pads allowed)
				(copperpour not_allowed)
				(footprints allowed)
			)
			(placement
				(enabled no)
				(sheetname "")
			)
			(fill
				(thermal_gap 0.5)
				(thermal_bridge_width 0.5)
				(island_removal_mode 0)
			)
			(polygon
				(pts
					(xy 458.812392 -38.337998) (xy 458.812392 -38.845998) (xy 458.431392 -38.845998) (xy 458.431392 -38.337998)
				)
			)
		)
	)
	(footprint ""
		(layer "F.Cu")
		(at 330.962 -148.463 180)
		(property "Reference" "C6A4"
			(at 0 0 180)
			(layer "F.SilkS")
			(hide yes)
			(effects
				(font
					(size 1.27 1.27)
				)
			)
		)
		(property "Value" ""
			(at 0 0 180)
			(layer "F.Fab")
			(effects
				(font
					(size 1.27 1.27)
				)
			)
		)
		(duplicate_pad_numbers_are_jumpers no)
		(fp_rect
			(start -0.7239 1.9939)
			(end 0.7239 -0.2159)
			(stroke
				(width 0)
				(type default)
			)
			(fill no)
			(layer "F.CrtYd")
		)
		(fp_line
			(start 0.7239 1.9939)
			(end 0.7239 -0.2159)
			(stroke
				(width 0.1)
				(type default)
			)
			(layer "F.Fab")
		)
		(fp_line
			(start 0.7239 -0.2159)
			(end -0.7239 -0.2159)
			(stroke
				(width 0.1)
				(type default)
			)
			(layer "F.Fab")
		)
		(fp_line
			(start -0.7239 1.9939)
			(end 0.7239 1.9939)
			(stroke
				(width 0.1)
				(type default)
			)
			(layer "F.Fab")
		)
		(fp_line
			(start -0.7239 -0.2159)
			(end -0.7239 1.9939)
			(stroke
				(width 0.1)
				(type default)
			)
			(layer "F.Fab")
		)
		(pad "1" smd rect
			(at 0 0 180)
			(size 1.27 1.016)
			(layers "F.Cu" "F.Mask" "F.Paste")
			(net "PVDDQ_DEF")
		)
		(pad "2" smd rect
			(at 0 1.778 180)
			(size 1.27 1.016)
			(layers "F.Cu" "F.Mask" "F.Paste")
			(net "GND")
		)
		(zone
			(layer "F.Cu")
			(hatch none 0.5)
			(connect_pads
				(clearance 0)
			)
			(min_thickness 0.25)
			(keepout
				(tracks not_allowed)
				(vias allowed)
				(pads allowed)
				(copperpour not_allowed)
				(footprints allowed)
			)
			(placement
				(enabled no)
				(sheetname "")
			)
			(fill
				(thermal_gap 0.5)
				(thermal_bridge_width 0.5)
				(island_removal_mode 0)
			)
			(polygon
				(pts
					(xy 331.597 -149.733) (xy 330.327 -149.733) (xy 330.327 -148.971) (xy 331.597 -148.971)
				)
			)
		)
	)
)
